(kicad_pcb
	(version 20260206)
	(generator "pcbnew")
	(generator_version "10.0")
	(general
		(thickness 1.6)
		(legacy_teardrops no)
	)
	(paper "A4")
	(title_block
		(title "03242023_DA0F0TMBIJ0_F0T_Motherboard_J_brd_V01_OCP.brd")
		(comment 1 "Grand Teton / footprints 79-84 of 6105")
	)
	(layers
		(0 "F.Cu" signal "TOP")
		(4 "In1.Cu" signal "GND")
		(6 "In2.Cu" signal "IN1")
		(8 "In3.Cu" signal "GND1")
		(10 "In4.Cu" signal "IN2")
		(12 "In5.Cu" signal "GND2")
		(14 "In6.Cu" signal "IN3")
		(16 "In7.Cu" signal "GND3")
		(18 "In8.Cu" signal "VCC")
		(20 "In9.Cu" signal "VCC1")
		(22 "In10.Cu" signal "GND4")
		(24 "In11.Cu" signal "IN4")
		(26 "In12.Cu" signal "GND5")
		(28 "In13.Cu" signal "IN5")
		(30 "In14.Cu" signal "GND6")
		(32 "In15.Cu" signal "IN6")
		(34 "In16.Cu" signal "GND7")
		(2 "B.Cu" signal "BOTTOM")
		(9 "F.Adhes" user "F.Adhesive")
		(11 "B.Adhes" user "B.Adhesive")
		(13 "F.Paste" user "Package Geometry/Pastemask Top")
		(15 "B.Paste" user "Package Geometry/Pastemask Bottom")
		(5 "F.SilkS" user "Ref Des/Silkscreen Top")
		(7 "B.SilkS" user "Ref Des/Silkscreen Bottom")
		(1 "F.Mask" user "Board Geometry/Soldermask Top")
		(3 "B.Mask" user "Board Geometry/Soldermask Bottom")
		(17 "Dwgs.User" user "User.Drawings")
		(19 "Cmts.User" user "User.Comments")
		(21 "Eco1.User" user "User.Eco1")
		(23 "Eco2.User" user "User.Eco2")
		(25 "Edge.Cuts" user "Board Geometry/Outline")
		(27 "Margin" user)
		(31 "F.CrtYd" user "Package Geometry/Place Bound Top")
		(29 "B.CrtYd" user "Package Geometry/Place Bound Bottom")
		(35 "F.Fab" user "Ref Des/Assembly Top")
		(33 "B.Fab" user "Ref Des/Assembly Bottom")
	)
	(footprint ""
		(layer "F.Cu")
		(at 304.09896 -430.65827 -90)
		(property "Reference" "C2267"
			(at 0 0 270)
			(layer "F.SilkS")
			(hide yes)
			(effects
				(font
					(size 1.27 1.27)
				)
			)
		)
		(property "Value" ""
			(at 0 0 270)
			(layer "F.Fab")
			(effects
				(font
					(size 1.27 1.27)
				)
			)
		)
		(duplicate_pad_numbers_are_jumpers no)
		(fp_line
			(start -0.7874 0.4064)
			(end -0.7874 -0.4064)
			(stroke
				(width 0.1524)
				(type default)
			)
			(layer "F.SilkS")
		)
		(fp_line
			(start 0.7874 0.4064)
			(end -0.7874 0.4064)
			(stroke
				(width 0.1524)
				(type default)
			)
			(layer "F.SilkS")
		)
		(fp_line
			(start -0.7874 -0.4064)
			(end 0.7874 -0.4064)
			(stroke
				(width 0.1524)
				(type default)
			)
			(layer "F.SilkS")
		)
		(fp_line
			(start 0.7874 -0.4064)
			(end 0.7874 0.4064)
			(stroke
				(width 0.1524)
				(type default)
			)
			(layer "F.SilkS")
		)
		(fp_line
			(start -0.67945 0.3048)
			(end -0.67945 -0.305054)
			(stroke
				(width 0.1)
				(type default)
			)
			(layer "F.Fab")
		)
		(fp_line
			(start -0.12065 0.3048)
			(end -0.67945 0.3048)
			(stroke
				(width 0.1)
				(type default)
			)
			(layer "F.Fab")
		)
		(fp_line
			(start 0.120396 0.3048)
			(end 0.120396 0.2794)
			(stroke
				(width 0.1)
				(type default)
			)
			(layer "F.Fab")
		)
		(fp_line
			(start 0.67945 0.3048)
			(end 0.120396 0.3048)
			(stroke
				(width 0.1)
				(type default)
			)
			(layer "F.Fab")
		)
		(fp_line
			(start -0.12065 0.2794)
			(end -0.12065 0.3048)
			(stroke
				(width 0.1)
				(type default)
			)
			(layer "F.Fab")
		)
		(fp_line
			(start 0.120396 0.2794)
			(end -0.12065 0.2794)
			(stroke
				(width 0.1)
				(type default)
			)
			(layer "F.Fab")
		)
		(fp_line
			(start -0.12065 -0.2794)
			(end 0.12065 -0.2794)
			(stroke
				(width 0.1)
				(type default)
			)
			(layer "F.Fab")
		)
		(fp_line
			(start 0.12065 -0.2794)
			(end 0.12065 -0.3048)
			(stroke
				(width 0.1)
				(type default)
			)
			(layer "F.Fab")
		)
		(fp_line
			(start 0.12065 -0.3048)
			(end 0.67945 -0.3048)
			(stroke
				(width 0.1)
				(type default)
			)
			(layer "F.Fab")
		)
		(fp_line
			(start 0.67945 -0.3048)
			(end 0.67945 0.3048)
			(stroke
				(width 0.1)
				(type default)
			)
			(layer "F.Fab")
		)
		(fp_line
			(start -0.67945 -0.305054)
			(end -0.12065 -0.305054)
			(stroke
				(width 0.1)
				(type default)
			)
			(layer "F.Fab")
		)
		(fp_line
			(start -0.12065 -0.305054)
			(end -0.12065 -0.2794)
			(stroke
				(width 0.1)
				(type default)
			)
			(layer "F.Fab")
		)
		(pad "1" smd circle
			(at -0.40005 0 270)
			(size 0 0)
			(layers "F.Cu" "F.Mask" "F.Paste")
			(net "GPU_3V3IO_RSVD3_FFU_ISO")
		)
		(pad "2" smd circle
			(at 0.40005 0 270)
			(size 0 0)
			(layers "F.Cu" "F.Mask" "F.Paste")
			(net "GND")
		)
	)
	(footprint ""
		(layer "F.Cu")
		(at 52.423314 -152.903174 180)
		(property "Reference" "PC440"
			(at 0 0 180)
			(layer "F.SilkS")
			(hide yes)
			(effects
				(font
					(size 1.27 1.27)
				)
			)
		)
		(property "Value" ""
			(at 0 0 180)
			(layer "F.Fab")
			(effects
				(font
					(size 1.27 1.27)
				)
			)
		)
		(duplicate_pad_numbers_are_jumpers no)
		(fp_line
			(start 0.7874 0.4064)
			(end -0.7874 0.4064)
			(stroke
				(width 0.1524)
				(type default)
			)
			(layer "F.SilkS")
		)
		(fp_line
			(start 0.7874 -0.4064)
			(end 0.7874 0.4064)
			(stroke
				(width 0.1524)
				(type default)
			)
			(layer "F.SilkS")
		)
		(fp_line
			(start -0.7874 0.4064)
			(end -0.7874 -0.4064)
			(stroke
				(width 0.1524)
				(type default)
			)
			(layer "F.SilkS")
		)
		(fp_line
			(start -0.7874 -0.4064)
			(end 0.7874 -0.4064)
			(stroke
				(width 0.1524)
				(type default)
			)
			(layer "F.SilkS")
		)
		(fp_line
			(start 0.67945 0.3048)
			(end 0.120396 0.3048)
			(stroke
				(width 0.1)
				(type default)
			)
			(layer "F.Fab")
		)
		(fp_line
			(start 0.67945 -0.3048)
			(end 0.67945 0.3048)
			(stroke
				(width 0.1)
				(type default)
			)
			(layer "F.Fab")
		)
		(fp_line
			(start 0.12065 -0.2794)
			(end 0.12065 -0.3048)
			(stroke
				(width 0.1)
				(type default)
			)
			(layer "F.Fab")
		)
		(fp_line
			(start 0.12065 -0.3048)
			(end 0.67945 -0.3048)
			(stroke
				(width 0.1)
				(type default)
			)
			(layer "F.Fab")
		)
		(fp_line
			(start 0.120396 0.3048)
			(end 0.120396 0.2794)
			(stroke
				(width 0.1)
				(type default)
			)
			(layer "F.Fab")
		)
		(fp_line
			(start 0.120396 0.2794)
			(end -0.12065 0.2794)
			(stroke
				(width 0.1)
				(type default)
			)
			(layer "F.Fab")
		)
		(fp_line
			(start -0.12065 0.3048)
			(end -0.67945 0.3048)
			(stroke
				(width 0.1)
				(type default)
			)
			(layer "F.Fab")
		)
		(fp_line
			(start -0.12065 0.2794)
			(end -0.12065 0.3048)
			(stroke
				(width 0.1)
				(type default)
			)
			(layer "F.Fab")
		)
		(fp_line
			(start -0.12065 -0.2794)
			(end 0.12065 -0.2794)
			(stroke
				(width 0.1)
				(type default)
			)
			(layer "F.Fab")
		)
		(fp_line
			(start -0.12065 -0.305054)
			(end -0.12065 -0.2794)
			(stroke
				(width 0.1)
				(type default)
			)
			(layer "F.Fab")
		)
		(fp_line
			(start -0.67945 0.3048)
			(end -0.67945 -0.305054)
			(stroke
				(width 0.1)
				(type default)
			)
			(layer "F.Fab")
		)
		(fp_line
			(start -0.67945 -0.305054)
			(end -0.12065 -0.305054)
			(stroke
				(width 0.1)
				(type default)
			)
			(layer "F.Fab")
		)
		(pad "1" smd circle
			(at -0.40005 0 180)
			(size 0 0)
			(layers "F.Cu" "F.Mask" "F.Paste")
			(net "PVCCINFAON_CPU1_VDD1")
		)
		(pad "2" smd circle
			(at 0.40005 0 180)
			(size 0 0)
			(layers "F.Cu" "F.Mask" "F.Paste")
			(net "GND")
		)
	)
	(footprint ""
		(layer "F.Cu")
		(at 445.175386 -47.627286 180)
		(property "Reference" "C1862"
			(at 0 0 180)
			(layer "F.SilkS")
			(hide yes)
			(effects
				(font
					(size 1.27 1.27)
				)
			)
		)
		(property "Value" ""
			(at 0 0 180)
			(layer "F.Fab")
			(effects
				(font
					(size 1.27 1.27)
				)
			)
		)
		(duplicate_pad_numbers_are_jumpers no)
		(fp_line
			(start 0.7874 0.4064)
			(end -0.7874 0.4064)
			(stroke
				(width 0.1524)
				(type default)
			)
			(layer "F.SilkS")
		)
		(fp_line
			(start 0.7874 -0.4064)
			(end 0.7874 0.4064)
			(stroke
				(width 0.1524)
				(type default)
			)
			(layer "F.SilkS")
		)
		(fp_line
			(start -0.7874 0.4064)
			(end -0.7874 -0.4064)
			(stroke
				(width 0.1524)
				(type default)
			)
			(layer "F.SilkS")
		)
		(fp_line
			(start -0.7874 -0.4064)
			(end 0.7874 -0.4064)
			(stroke
				(width 0.1524)
				(type default)
			)
			(layer "F.SilkS")
		)
		(fp_line
			(start 0.67945 0.3048)
			(end 0.120396 0.3048)
			(stroke
				(width 0.1)
				(type default)
			)
			(layer "F.Fab")
		)
		(fp_line
			(start 0.67945 -0.3048)
			(end 0.67945 0.3048)
			(stroke
				(width 0.1)
				(type default)
			)
			(layer "F.Fab")
		)
		(fp_line
			(start 0.12065 -0.2794)
			(end 0.12065 -0.3048)
			(stroke
				(width 0.1)
				(type default)
			)
			(layer "F.Fab")
		)
		(fp_line
			(start 0.12065 -0.3048)
			(end 0.67945 -0.3048)
			(stroke
				(width 0.1)
				(type default)
			)
			(layer "F.Fab")
		)
		(fp_line
			(start 0.120396 0.3048)
			(end 0.120396 0.2794)
			(stroke
				(width 0.1)
				(type default)
			)
			(layer "F.Fab")
		)
		(fp_line
			(start 0.120396 0.2794)
			(end -0.12065 0.2794)
			(stroke
				(width 0.1)
				(type default)
			)
			(layer "F.Fab")
		)
		(fp_line
			(start -0.12065 0.3048)
			(end -0.67945 0.3048)
			(stroke
				(width 0.1)
				(type default)
			)
			(layer "F.Fab")
		)
		(fp_line
			(start -0.12065 0.2794)
			(end -0.12065 0.3048)
			(stroke
				(width 0.1)
				(type default)
			)
			(layer "F.Fab")
		)
		(fp_line
			(start -0.12065 -0.2794)
			(end 0.12065 -0.2794)
			(stroke
				(width 0.1)
				(type default)
			)
			(layer "F.Fab")
		)
		(fp_line
			(start -0.12065 -0.305054)
			(end -0.12065 -0.2794)
			(stroke
				(width 0.1)
				(type default)
			)
			(layer "F.Fab")
		)
		(fp_line
			(start -0.67945 0.3048)
			(end -0.67945 -0.305054)
			(stroke
				(width 0.1)
				(type default)
			)
			(layer "F.Fab")
		)
		(fp_line
			(start -0.67945 -0.305054)
			(end -0.12065 -0.305054)
			(stroke
				(width 0.1)
				(type default)
			)
			(layer "F.Fab")
		)
		(pad "1" smd circle
			(at -0.40005 0 180)
			(size 0 0)
			(layers "F.Cu" "F.Mask" "F.Paste")
			(net "P3V3_OCP_SFF")
		)
		(pad "2" smd circle
			(at 0.40005 0 180)
			(size 0 0)
			(layers "F.Cu" "F.Mask" "F.Paste")
			(net "GND")
		)
	)
	(footprint ""
		(layer "F.Cu")
		(at 29.035756 -133.04139)
		(property "Reference" "PC469"
			(at 0 0 0)
			(layer "F.SilkS")
			(hide yes)
			(effects
				(font
					(size 1.27 1.27)
				)
			)
		)
		(property "Value" ""
			(at 0 0 0)
			(layer "F.Fab")
			(effects
				(font
					(size 1.27 1.27)
				)
			)
		)
		(duplicate_pad_numbers_are_jumpers no)
		(fp_line
			(start -0.7874 -0.4064)
			(end 0.7874 -0.4064)
			(stroke
				(width 0.1524)
				(type default)
			)
			(layer "F.SilkS")
		)
		(fp_line
			(start -0.7874 0.4064)
			(end -0.7874 -0.4064)
			(stroke
				(width 0.1524)
				(type default)
			)
			(layer "F.SilkS")
		)
		(fp_line
			(start 0.7874 -0.4064)
			(end 0.7874 0.4064)
			(stroke
				(width 0.1524)
				(type default)
			)
			(layer "F.SilkS")
		)
		(fp_line
			(start 0.7874 0.4064)
			(end -0.7874 0.4064)
			(stroke
				(width 0.1524)
				(type default)
			)
			(layer "F.SilkS")
		)
		(fp_line
			(start -0.67945 -0.305054)
			(end -0.12065 -0.305054)
			(stroke
				(width 0.1)
				(type default)
			)
			(layer "F.Fab")
		)
		(fp_line
			(start -0.67945 0.3048)
			(end -0.67945 -0.305054)
			(stroke
				(width 0.1)
				(type default)
			)
			(layer "F.Fab")
		)
		(fp_line
			(start -0.12065 -0.305054)
			(end -0.12065 -0.2794)
			(stroke
				(width 0.1)
				(type default)
			)
			(layer "F.Fab")
		)
		(fp_line
			(start -0.12065 -0.2794)
			(end 0.12065 -0.2794)
			(stroke
				(width 0.1)
				(type default)
			)
			(layer "F.Fab")
		)
		(fp_line
			(start -0.12065 0.2794)
			(end -0.12065 0.3048)
			(stroke
				(width 0.1)
				(type default)
			)
			(layer "F.Fab")
		)
		(fp_line
			(start -0.12065 0.3048)
			(end -0.67945 0.3048)
			(stroke
				(width 0.1)
				(type default)
			)
			(layer "F.Fab")
		)
		(fp_line
			(start 0.120396 0.2794)
			(end -0.12065 0.2794)
			(stroke
				(width 0.1)
				(type default)
			)
			(layer "F.Fab")
		)
		(fp_line
			(start 0.120396 0.3048)
			(end 0.120396 0.2794)
			(stroke
				(width 0.1)
				(type default)
			)
			(layer "F.Fab")
		)
		(fp_line
			(start 0.12065 -0.3048)
			(end 0.67945 -0.3048)
			(stroke
				(width 0.1)
				(type default)
			)
			(layer "F.Fab")
		)
		(fp_line
			(start 0.12065 -0.2794)
			(end 0.12065 -0.3048)
			(stroke
				(width 0.1)
				(type default)
			)
			(layer "F.Fab")
		)
		(fp_line
			(start 0.67945 -0.3048)
			(end 0.67945 0.3048)
			(stroke
				(width 0.1)
				(type default)
			)
			(layer "F.Fab")
		)
		(fp_line
			(start 0.67945 0.3048)
			(end 0.120396 0.3048)
			(stroke
				(width 0.1)
				(type default)
			)
			(layer "F.Fab")
		)
		(pad "1" smd circle
			(at -0.40005 0)
			(size 0 0)
			(layers "F.Cu" "F.Mask" "F.Paste")
			(net "SH_PVCCFA_EHV_CPU1_R")
		)
		(pad "2" smd circle
			(at 0.40005 0)
			(size 0 0)
			(layers "F.Cu" "F.Mask" "F.Paste")
			(net "VSENSE_PVCCFA_EHV_CPU1_DN")
		)
	)
	(footprint ""
		(layer "F.Cu")
		(at 22.460204 -385.778248 -90)
		(property "Reference" "C1869"
			(at 0 0 270)
			(layer "F.SilkS")
			(hide yes)
			(effects
				(font
					(size 1.27 1.27)
				)
			)
		)
		(property "Value" ""
			(at 0 0 270)
			(layer "F.Fab")
			(effects
				(font
					(size 1.27 1.27)
				)
			)
		)
		(duplicate_pad_numbers_are_jumpers no)
		(fp_line
			(start 0.7874 0.4064)
			(end -0.7874 0.4064)
			(stroke
				(width 0.1524)
				(type default)
			)
			(layer "F.SilkS")
		)
		(fp_line
			(start -0.7874 -0.4064)
			(end 0.000508 -0.4064)
			(stroke
				(width 0.1524)
				(type default)
			)
			(layer "F.SilkS")
		)
		(fp_line
			(start 0.7874 -0.4064)
			(end 0.7874 0.4064)
			(stroke
				(width 0.1524)
				(type default)
			)
			(layer "F.SilkS")
		)
		(fp_line
			(start -0.6858 0.3048)
			(end -0.6858 -0.3048)
			(stroke
				(width 0.1)
				(type default)
			)
			(layer "F.Fab")
		)
		(fp_line
			(start -0.1016 0.3048)
			(end -0.6858 0.3048)
			(stroke
				(width 0.1)
				(type default)
			)
			(layer "F.Fab")
		)
		(fp_line
			(start 0.1016 0.3048)
			(end 0.1016 0.2794)
			(stroke
				(width 0.1)
				(type default)
			)
			(layer "F.Fab")
		)
		(fp_line
			(start 0.6858 0.3048)
			(end 0.1016 0.3048)
			(stroke
				(width 0.1)
				(type default)
			)
			(layer "F.Fab")
		)
		(fp_line
			(start -0.1016 0.2794)
			(end -0.1016 0.3048)
			(stroke
				(width 0.1)
				(type default)
			)
			(layer "F.Fab")
		)
		(fp_line
			(start 0.1016 0.2794)
			(end -0.1016 0.2794)
			(stroke
				(width 0.1)
				(type default)
			)
			(layer "F.Fab")
		)
		(fp_line
			(start -0.1016 -0.2794)
			(end 0.1016 -0.2794)
			(stroke
				(width 0.1)
				(type default)
			)
			(layer "F.Fab")
		)
		(fp_line
			(start 0.1016 -0.2794)
			(end 0.1016 -0.3048)
			(stroke
				(width 0.1)
				(type default)
			)
			(layer "F.Fab")
		)
		(fp_line
			(start -0.6858 -0.3048)
			(end -0.1016 -0.3048)
			(stroke
				(width 0.1)
				(type default)
			)
			(layer "F.Fab")
		)
		(fp_line
			(start -0.1016 -0.3048)
			(end -0.1016 -0.2794)
			(stroke
				(width 0.1)
				(type default)
			)
			(layer "F.Fab")
		)
		(fp_line
			(start 0.1016 -0.3048)
			(end 0.6858 -0.3048)
			(stroke
				(width 0.1)
				(type default)
			)
			(layer "F.Fab")
		)
		(fp_line
			(start 0.6858 -0.3048)
			(end 0.6858 0.3048)
			(stroke
				(width 0.1)
				(type default)
			)
			(layer "F.Fab")
		)
		(pad "1" smd rect
			(at -0.40005 0 90)
			(size 0.4572 0.508)
			(layers "F.Cu" "F.Mask" "F.Paste")
			(net "P2E_MB_BMC_RX_BUF_C_DN<0>")
		)
		(pad "2" smd rect
			(at 0.40005 0 90)
			(size 0.4572 0.508)
			(layers "F.Cu" "F.Mask" "F.Paste")
			(net "P2E_MB_BMC_RX_BUF_DN<0>")
		)
	)
	(footprint ""
		(layer "F.Cu")
		(at 432.085496 -109.13745 90)
		(property "Reference" "PR3780"
			(at 0 0 90)
			(layer "F.SilkS")
			(hide yes)
			(effects
				(font
					(size 1.27 1.27)
				)
			)
		)
		(property "Value" ""
			(at 0 0 90)
			(layer "F.Fab")
			(effects
				(font
					(size 1.27 1.27)
				)
			)
		)
		(duplicate_pad_numbers_are_jumpers no)
		(fp_line
			(start 0.7874 -0.4064)
			(end 0.7874 0.4064)
			(stroke
				(width 0.1524)
				(type default)
			)
			(layer "F.SilkS")
		)
		(fp_line
			(start -0.7874 -0.4064)
			(end 0.7874 -0.4064)
			(stroke
				(width 0.1524)
				(type default)
			)
			(layer "F.SilkS")
		)
		(fp_line
			(start 0.7874 0.4064)
			(end -0.7874 0.4064)
			(stroke
				(width 0.1524)
				(type default)
			)
			(layer "F.SilkS")
		)
		(fp_line
			(start -0.7874 0.4064)
			(end -0.7874 -0.4064)
			(stroke
				(width 0.1524)
				(type default)
			)
			(layer "F.SilkS")
		)
		(fp_line
			(start -0.12065 -0.305054)
			(end -0.12065 -0.2794)
			(stroke
				(width 0.1)
				(type default)
			)
			(layer "F.Fab")
		)
		(fp_line
			(start -0.67945 -0.305054)
			(end -0.12065 -0.305054)
			(stroke
				(width 0.1)
				(type default)
			)
			(layer "F.Fab")
		)
		(fp_line
			(start 0.67945 -0.3048)
			(end 0.67945 0.3048)
			(stroke
				(width 0.1)
				(type default)
			)
			(layer "F.Fab")
		)
		(fp_line
			(start 0.12065 -0.3048)
			(end 0.67945 -0.3048)
			(stroke
				(width 0.1)
				(type default)
			)
			(layer "F.Fab")
		)
		(fp_line
			(start 0.12065 -0.2794)
			(end 0.12065 -0.3048)
			(stroke
				(width 0.1)
				(type default)
			)
			(layer "F.Fab")
		)
		(fp_line
			(start -0.12065 -0.2794)
			(end 0.12065 -0.2794)
			(stroke
				(width 0.1)
				(type default)
			)
			(layer "F.Fab")
		)
		(fp_line
			(start 0.120396 0.2794)
			(end -0.12065 0.2794)
			(stroke
				(width 0.1)
				(type default)
			)
			(layer "F.Fab")
		)
		(fp_line
			(start -0.12065 0.2794)
			(end -0.12065 0.3048)
			(stroke
				(width 0.1)
				(type default)
			)
			(layer "F.Fab")
		)
		(fp_line
			(start 0.67945 0.3048)
			(end 0.120396 0.3048)
			(stroke
				(width 0.1)
				(type default)
			)
			(layer "F.Fab")
		)
		(fp_line
			(start 0.120396 0.3048)
			(end 0.120396 0.2794)
			(stroke
				(width 0.1)
				(type default)
			)
			(layer "F.Fab")
		)
		(fp_line
			(start -0.12065 0.3048)
			(end -0.67945 0.3048)
			(stroke
				(width 0.1)
				(type default)
			)
			(layer "F.Fab")
		)
		(fp_line
			(start -0.67945 0.3048)
			(end -0.67945 -0.305054)
			(stroke
				(width 0.1)
				(type default)
			)
			(layer "F.Fab")
		)
		(pad "1" smd circle
			(at -0.40005 0 90)
			(size 0 0)
			(layers "F.Cu" "F.Mask" "F.Paste")
			(net "P3V3_OCP_CB_1")
		)
		(pad "2" smd circle
			(at 0.40005 0 90)
			(size 0 0)
			(layers "F.Cu" "F.Mask" "F.Paste")
			(net "GND")
		)
	)
)
